# BASEBOARD_FAB2 (Tioga Pass) — schematic netlist excerpt (pin names and nets, part order shuffled) for the footprints in the layout excerpt that follows; sources: Cadence DE-HDL packaged netlist, KiCad conversion of Wiwynn_Tioga_Pass_MB.brd

C3D3  CAP  10UF 4V 20% X6S  pkg 0603LF  page 72 : A = P1V8_MCP_CPU1 ; B = GND
C7R1  CAP_A  22.0UF 4V 20% X6S  pkg 0603V  page 214 : A = PVCCIO_CPU1 ; B = GND
R2T42  RES  22.1 1.0% CHIP  pkg 0402  page 101 : A = CLK_50M_CKMNG_OCP_R ; B = CLK_50M_CKMNG_OCP

(kicad_pcb
	(version 20260206)
	(generator "pcbnew")
	(generator_version "10.0")
	(general
		(thickness 1.6)
		(legacy_teardrops no)
	)
	(paper "A4")
	(title_block
		(title "Wiwynn_Tioga_Pass_MB.brd")
		(comment 1 "Tioga Pass / footprints 2304-2306 of 4770")
	)
	(layers
		(0 "F.Cu" signal "TOP")
		(4 "In1.Cu" signal "L2GND")
		(6 "In2.Cu" signal "L3")
		(8 "In3.Cu" signal "L4GND")
		(10 "In4.Cu" signal "L5")
		(12 "In5.Cu" signal "L6GND")
		(14 "In6.Cu" signal "L7VCC")
		(16 "In7.Cu" signal "L8VCC")
		(18 "In8.Cu" signal "L9GND")
		(20 "In9.Cu" signal "L10")
		(22 "In10.Cu" signal "L11GND")
		(24 "In11.Cu" signal "L12")
		(26 "In12.Cu" signal "L13GND")
		(2 "B.Cu" signal "BOTTOM")
		(9 "F.Adhes" user "F.Adhesive")
		(11 "B.Adhes" user "B.Adhesive")
		(13 "F.Paste" user "Package Geometry/Pastemask Top")
		(15 "B.Paste" user "Package Geometry/Pastemask Bottom")
		(5 "F.SilkS" user "Ref Des/Silkscreen Top")
		(7 "B.SilkS" user "Ref Des/Silkscreen Bottom")
		(1 "F.Mask" user "Board Geometry/Soldermask Top")
		(3 "B.Mask" user "Board Geometry/Soldermask Bottom")
		(17 "Dwgs.User" user "User.Drawings")
		(19 "Cmts.User" user "User.Comments")
		(21 "Eco1.User" user "User.Eco1")
		(23 "Eco2.User" user "User.Eco2")
		(25 "Edge.Cuts" user "Board Geometry/Outline")
		(27 "Margin" user)
		(31 "F.CrtYd" user "Package Geometry/Place Bound Top")
		(29 "B.CrtYd" user "Package Geometry/Place Bound Bottom")
		(35 "F.Fab" user "Ref Des/Assembly Top")
		(33 "B.Fab" user "Ref Des/Assembly Bottom")
	)
	(footprint ""
		(layer "F.Cu")
		(at 161.798 -63.373)
		(property "Reference" "C7R1"
			(at 0 0 0)
			(layer "F.SilkS")
			(hide yes)
			(effects
				(font
					(size 1.27 1.27)
				)
			)
		)
		(property "Value" ""
			(at 0 0 0)
			(layer "F.Fab")
			(effects
				(font
					(size 1.27 1.27)
				)
			)
		)
		(duplicate_pad_numbers_are_jumpers no)
		(fp_poly
			(pts
				(xy -0.4953 -0.2032) (xy 0.4953 -0.2032) (xy 0.4953 1.6002) (xy -0.4953 1.6002)
			)
			(stroke
				(width 0)
				(type default)
			)
			(fill no)
			(layer "F.CrtYd")
		)
		(fp_line
			(start -0.4953 -0.2032)
			(end 0.4953 -0.2032)
			(stroke
				(width 0.1)
				(type default)
			)
			(layer "F.Fab")
		)
		(fp_line
			(start -0.4953 1.6002)
			(end -0.4953 -0.2032)
			(stroke
				(width 0.1)
				(type default)
			)
			(layer "F.Fab")
		)
		(fp_line
			(start 0.4953 -0.2032)
			(end 0.4953 1.6002)
			(stroke
				(width 0.1)
				(type default)
			)
			(layer "F.Fab")
		)
		(fp_line
			(start 0.4953 1.6002)
			(end -0.4953 1.6002)
			(stroke
				(width 0.1)
				(type default)
			)
			(layer "F.Fab")
		)
		(pad "1" smd rect
			(at 0 0)
			(size 0.762 0.889)
			(layers "F.Cu" "F.Mask" "F.Paste")
			(net "PVCCIO_CPU1")
		)
		(pad "2" smd rect
			(at 0 1.397)
			(size 0.762 0.889)
			(layers "F.Cu" "F.Mask" "F.Paste")
			(net "GND")
		)
		(zone
			(layer "F.Cu")
			(hatch none 0.5)
			(connect_pads
				(clearance 0)
			)
			(min_thickness 0.25)
			(keepout
				(tracks not_allowed)
				(vias allowed)
				(pads allowed)
				(copperpour not_allowed)
				(footprints allowed)
			)
			(placement
				(enabled no)
				(sheetname "")
			)
			(fill
				(thermal_gap 0.5)
				(thermal_bridge_width 0.5)
				(island_removal_mode 0)
			)
			(polygon
				(pts
					(xy 161.417 -62.9285) (xy 162.179 -62.9285) (xy 162.179 -62.4205) (xy 161.417 -62.4205)
				)
			)
		)
	)
	(footprint ""
		(layer "F.Cu")
		(at 116.369592 -81.366614)
		(property "Reference" "C3D3"
			(at 0 0 0)
			(layer "F.SilkS")
			(hide yes)
			(effects
				(font
					(size 1.27 1.27)
				)
			)
		)
		(property "Value" ""
			(at 0 0 0)
			(layer "F.Fab")
			(effects
				(font
					(size 1.27 1.27)
				)
			)
		)
		(duplicate_pad_numbers_are_jumpers no)
		(fp_poly
			(pts
				(xy -0.4953 -0.2032) (xy 0.4953 -0.2032) (xy 0.4953 1.6002) (xy -0.4953 1.6002)
			)
			(stroke
				(width 0)
				(type default)
			)
			(fill no)
			(layer "F.CrtYd")
		)
		(fp_line
			(start -0.4953 -0.2032)
			(end 0.4953 -0.2032)
			(stroke
				(width 0.1)
				(type default)
			)
			(layer "F.Fab")
		)
		(fp_line
			(start -0.4953 1.6002)
			(end -0.4953 -0.2032)
			(stroke
				(width 0.1)
				(type default)
			)
			(layer "F.Fab")
		)
		(fp_line
			(start 0.4953 -0.2032)
			(end 0.4953 1.6002)
			(stroke
				(width 0.1)
				(type default)
			)
			(layer "F.Fab")
		)
		(fp_line
			(start 0.4953 1.6002)
			(end -0.4953 1.6002)
			(stroke
				(width 0.1)
				(type default)
			)
			(layer "F.Fab")
		)
		(pad "1" smd rect
			(at 0 0)
			(size 0.762 0.889)
			(layers "F.Cu" "F.Mask" "F.Paste")
			(net "P1V8_MCP_CPU1")
		)
		(pad "2" smd rect
			(at 0 1.397)
			(size 0.762 0.889)
			(layers "F.Cu" "F.Mask" "F.Paste")
			(net "GND")
		)
		(zone
			(layer "F.Cu")
			(hatch none 0.5)
			(connect_pads
				(clearance 0)
			)
			(min_thickness 0.25)
			(keepout
				(tracks not_allowed)
				(vias allowed)
				(pads allowed)
				(copperpour not_allowed)
				(footprints allowed)
			)
			(placement
				(enabled no)
				(sheetname "")
			)
			(fill
				(thermal_gap 0.5)
				(thermal_bridge_width 0.5)
				(island_removal_mode 0)
			)
			(polygon
				(pts
					(xy 115.988592 -80.922114) (xy 116.750592 -80.922114) (xy 116.750592 -80.414114) (xy 115.988592 -80.414114)
				)
			)
		)
	)
	(footprint ""
		(layer "F.Cu")
		(at 474.091 -35.7505 180)
		(property "Reference" "R2T42"
			(at 0 0 180)
			(layer "F.SilkS")
			(hide yes)
			(effects
				(font
					(size 1.27 1.27)
				)
			)
		)
		(property "Value" ""
			(at 0 0 180)
			(layer "F.Fab")
			(effects
				(font
					(size 1.27 1.27)
				)
			)
		)
		(duplicate_pad_numbers_are_jumpers no)
		(fp_poly
			(pts
				(xy -0.2794 -0.1016) (xy 0.2794 -0.1016) (xy 0.2794 0.9906) (xy -0.2794 0.9906)
			)
			(stroke
				(width 0)
				(type default)
			)
			(fill no)
			(layer "F.CrtYd")
		)
		(fp_line
			(start 0.2794 0.9906)
			(end 0.2794 -0.1016)
			(stroke
				(width 0.1)
				(type default)
			)
			(layer "F.Fab")
		)
		(fp_line
			(start 0.2794 -0.1016)
			(end -0.2794 -0.1016)
			(stroke
				(width 0.1)
				(type default)
			)
			(layer "F.Fab")
		)
		(fp_line
			(start -0.2794 0.9906)
			(end 0.2794 0.9906)
			(stroke
				(width 0.1)
				(type default)
			)
			(layer "F.Fab")
		)
		(fp_line
			(start -0.2794 -0.1016)
			(end -0.2794 0.9906)
			(stroke
				(width 0.1)
				(type default)
			)
			(layer "F.Fab")
		)
		(pad "1" smd rect
			(at 0 0 180)
			(size 0.508 0.508)
			(layers "F.Cu" "F.Mask" "F.Paste")
			(net "CLK_50M_CKMNG_OCP_R")
		)
		(pad "2" smd rect
			(at 0 0.889 180)
			(size 0.508 0.508)
			(layers "F.Cu" "F.Mask" "F.Paste")
			(net "CLK_50M_CKMNG_OCP")
		)
		(zone
			(layer "F.Cu")
			(hatch none 0.5)
			(connect_pads
				(clearance 0)
			)
			(min_thickness 0.25)
			(keepout
				(tracks not_allowed)
				(vias allowed)
				(pads allowed)
				(copperpour not_allowed)
				(footprints allowed)
			)
			(placement
				(enabled no)
				(sheetname "")
			)
			(fill
				(thermal_gap 0.5)
				(thermal_bridge_width 0.5)
				(island_removal_mode 0)
			)
			(polygon
				(pts
					(xy 474.345 -36.3855) (xy 473.837 -36.3855) (xy 473.837 -36.0045) (xy 474.345 -36.0045)
				)
			)
		)
		(zone
			(layer "F.Cu")
			(hatch none 0.5)
			(connect_pads
				(clearance 0)
			)
			(min_thickness 0.25)
			(keepout
				(tracks allowed)
				(vias not_allowed)
				(pads allowed)
				(copperpour not_allowed)
				(footprints allowed)
			)
			(placement
				(enabled no)
				(sheetname "")
			)
			(fill
				(thermal_gap 0.5)
				(thermal_bridge_width 0.5)
				(island_removal_mode 0)
			)
			(polygon
				(pts
					(xy 474.345 -36.0045) (xy 473.837 -36.0045) (xy 473.837 -36.3855) (xy 474.345 -36.3855)
				)
			)
		)
	)
)
